# T6G (Grand Teton) — schematic netlist excerpt (pin names and nets, part order shuffled) for the footprints in the layout excerpt that follows; sources: Cadence DE-HDL packaged netlist, KiCad conversion of 04192023_DAF0TMB3IC0_F0TG_MB_C_brd_V02_OCP.brd

PR4526  Q_RES  10M 1% CHIP  pkg 0402LF  page 152 : A = P12V_SCM_R ; B = P12V_SCM_GATE
PR14  Q_RES  0 5% CHIP  pkg 0402LF  page 224 : A = NC_PVDD11_S3_P1_IMON6 ; B = GND

(kicad_pcb
	(version 20260206)
	(generator "pcbnew")
	(generator_version "10.0")
	(general
		(thickness 1.6)
		(legacy_teardrops no)
	)
	(paper "A4")
	(title_block
		(title "04192023_DAF0TMB3IC0_F0TG_MB_C_brd_V02_OCP.brd")
		(comment 1 "Grand Teton / footprints 4171-4172 of 8354")
	)
	(layers
		(0 "F.Cu" signal "TOP")
		(4 "In1.Cu" signal "GND")
		(6 "In2.Cu" signal "IN1")
		(8 "In3.Cu" signal "GND1")
		(10 "In4.Cu" signal "IN2")
		(12 "In5.Cu" signal "GND2")
		(14 "In6.Cu" signal "IN3")
		(16 "In7.Cu" signal "GND3")
		(18 "In8.Cu" signal "VCC")
		(20 "In9.Cu" signal "VCC1")
		(22 "In10.Cu" signal "GND4")
		(24 "In11.Cu" signal "IN4")
		(26 "In12.Cu" signal "GND5")
		(28 "In13.Cu" signal "IN5")
		(30 "In14.Cu" signal "GND6")
		(32 "In15.Cu" signal "IN6")
		(34 "In16.Cu" signal "GND7")
		(2 "B.Cu" signal "BOTTOM")
		(9 "F.Adhes" user "F.Adhesive")
		(11 "B.Adhes" user "B.Adhesive")
		(13 "F.Paste" user "Package Geometry/Pastemask Top")
		(15 "B.Paste" user "Package Geometry/Pastemask Bottom")
		(5 "F.SilkS" user "Ref Des/Silkscreen Top")
		(7 "B.SilkS" user "Ref Des/Silkscreen Bottom")
		(1 "F.Mask" user "Board Geometry/Soldermask Top")
		(3 "B.Mask" user "Board Geometry/Soldermask Bottom")
		(17 "Dwgs.User" user "User.Drawings")
		(19 "Cmts.User" user "User.Comments")
		(21 "Eco1.User" user "User.Eco1")
		(23 "Eco2.User" user "User.Eco2")
		(25 "Edge.Cuts" user "Board Geometry/Outline")
		(27 "Margin" user)
		(31 "F.CrtYd" user "Package Geometry/Place Bound Top")
		(29 "B.CrtYd" user "Package Geometry/Place Bound Bottom")
		(35 "F.Fab" user "Ref Des/Assembly Top")
		(33 "B.Fab" user "Ref Des/Assembly Bottom")
	)
	(footprint ""
		(layer "F.Cu")
		(at 191.29629 -30.269688 180)
		(property "Reference" "PR4526"
			(at 0 0 180)
			(layer "F.SilkS")
			(hide yes)
			(effects
				(font
					(size 1.27 1.27)
				)
			)
		)
		(property "Value" ""
			(at 0 0 180)
			(layer "F.Fab")
			(effects
				(font
					(size 1.27 1.27)
				)
			)
		)
		(duplicate_pad_numbers_are_jumpers no)
		(fp_line
			(start 0.7874 0.4064)
			(end -0.7874 0.4064)
			(stroke
				(width 0.1524)
				(type default)
			)
			(layer "F.SilkS")
		)
		(fp_line
			(start 0.7874 -0.4064)
			(end 0.7874 0.4064)
			(stroke
				(width 0.1524)
				(type default)
			)
			(layer "F.SilkS")
		)
		(fp_line
			(start -0.7874 0.4064)
			(end -0.7874 -0.4064)
			(stroke
				(width 0.1524)
				(type default)
			)
			(layer "F.SilkS")
		)
		(fp_line
			(start -0.7874 -0.4064)
			(end 0.7874 -0.4064)
			(stroke
				(width 0.1524)
				(type default)
			)
			(layer "F.SilkS")
		)
		(fp_line
			(start 0.67945 0.3048)
			(end 0.120396 0.3048)
			(stroke
				(width 0.1)
				(type default)
			)
			(layer "F.Fab")
		)
		(fp_line
			(start 0.67945 -0.3048)
			(end 0.67945 0.3048)
			(stroke
				(width 0.1)
				(type default)
			)
			(layer "F.Fab")
		)
		(fp_line
			(start 0.12065 -0.2794)
			(end 0.12065 -0.3048)
			(stroke
				(width 0.1)
				(type default)
			)
			(layer "F.Fab")
		)
		(fp_line
			(start 0.12065 -0.3048)
			(end 0.67945 -0.3048)
			(stroke
				(width 0.1)
				(type default)
			)
			(layer "F.Fab")
		)
		(fp_line
			(start 0.120396 0.3048)
			(end 0.120396 0.2794)
			(stroke
				(width 0.1)
				(type default)
			)
			(layer "F.Fab")
		)
		(fp_line
			(start 0.120396 0.2794)
			(end -0.12065 0.2794)
			(stroke
				(width 0.1)
				(type default)
			)
			(layer "F.Fab")
		)
		(fp_line
			(start -0.12065 0.3048)
			(end -0.67945 0.3048)
			(stroke
				(width 0.1)
				(type default)
			)
			(layer "F.Fab")
		)
		(fp_line
			(start -0.12065 0.2794)
			(end -0.12065 0.3048)
			(stroke
				(width 0.1)
				(type default)
			)
			(layer "F.Fab")
		)
		(fp_line
			(start -0.12065 -0.2794)
			(end 0.12065 -0.2794)
			(stroke
				(width 0.1)
				(type default)
			)
			(layer "F.Fab")
		)
		(fp_line
			(start -0.12065 -0.305054)
			(end -0.12065 -0.2794)
			(stroke
				(width 0.1)
				(type default)
			)
			(layer "F.Fab")
		)
		(fp_line
			(start -0.67945 0.3048)
			(end -0.67945 -0.305054)
			(stroke
				(width 0.1)
				(type default)
			)
			(layer "F.Fab")
		)
		(fp_line
			(start -0.67945 -0.305054)
			(end -0.12065 -0.305054)
			(stroke
				(width 0.1)
				(type default)
			)
			(layer "F.Fab")
		)
		(pad "1" smd circle
			(at -0.40005 0 180)
			(size 0 0)
			(layers "F.Cu" "F.Mask" "F.Paste")
			(net "P12V_SCM_R")
		)
		(pad "2" smd circle
			(at 0.40005 0 180)
			(size 0 0)
			(layers "F.Cu" "F.Mask" "F.Paste")
			(net "P12V_SCM_GATE")
		)
	)
	(footprint ""
		(layer "F.Cu")
		(at 165.109144 -344.153998 -90)
		(property "Reference" "PR14"
			(at 0 0 270)
			(layer "F.SilkS")
			(hide yes)
			(effects
				(font
					(size 1.27 1.27)
				)
			)
		)
		(property "Value" ""
			(at 0 0 270)
			(layer "F.Fab")
			(effects
				(font
					(size 1.27 1.27)
				)
			)
		)
		(duplicate_pad_numbers_are_jumpers no)
		(fp_line
			(start -0.7874 0.4064)
			(end -0.7874 -0.4064)
			(stroke
				(width 0.1524)
				(type default)
			)
			(layer "F.SilkS")
		)
		(fp_line
			(start 0.7874 0.4064)
			(end -0.7874 0.4064)
			(stroke
				(width 0.1524)
				(type default)
			)
			(layer "F.SilkS")
		)
		(fp_line
			(start -0.7874 -0.4064)
			(end 0.7874 -0.4064)
			(stroke
				(width 0.1524)
				(type default)
			)
			(layer "F.SilkS")
		)
		(fp_line
			(start 0.7874 -0.4064)
			(end 0.7874 0.4064)
			(stroke
				(width 0.1524)
				(type default)
			)
			(layer "F.SilkS")
		)
		(fp_line
			(start -0.67945 0.3048)
			(end -0.67945 -0.305054)
			(stroke
				(width 0.1)
				(type default)
			)
			(layer "F.Fab")
		)
		(fp_line
			(start -0.12065 0.3048)
			(end -0.67945 0.3048)
			(stroke
				(width 0.1)
				(type default)
			)
			(layer "F.Fab")
		)
		(fp_line
			(start 0.120396 0.3048)
			(end 0.120396 0.2794)
			(stroke
				(width 0.1)
				(type default)
			)
			(layer "F.Fab")
		)
		(fp_line
			(start 0.67945 0.3048)
			(end 0.120396 0.3048)
			(stroke
				(width 0.1)
				(type default)
			)
			(layer "F.Fab")
		)
		(fp_line
			(start -0.12065 0.2794)
			(end -0.12065 0.3048)
			(stroke
				(width 0.1)
				(type default)
			)
			(layer "F.Fab")
		)
		(fp_line
			(start 0.120396 0.2794)
			(end -0.12065 0.2794)
			(stroke
				(width 0.1)
				(type default)
			)
			(layer "F.Fab")
		)
		(fp_line
			(start -0.12065 -0.2794)
			(end 0.12065 -0.2794)
			(stroke
				(width 0.1)
				(type default)
			)
			(layer "F.Fab")
		)
		(fp_line
			(start 0.12065 -0.2794)
			(end 0.12065 -0.3048)
			(stroke
				(width 0.1)
				(type default)
			)
			(layer "F.Fab")
		)
		(fp_line
			(start 0.12065 -0.3048)
			(end 0.67945 -0.3048)
			(stroke
				(width 0.1)
				(type default)
			)
			(layer "F.Fab")
		)
		(fp_line
			(start 0.67945 -0.3048)
			(end 0.67945 0.3048)
			(stroke
				(width 0.1)
				(type default)
			)
			(layer "F.Fab")
		)
		(fp_line
			(start -0.67945 -0.305054)
			(end -0.12065 -0.305054)
			(stroke
				(width 0.1)
				(type default)
			)
			(layer "F.Fab")
		)
		(fp_line
			(start -0.12065 -0.305054)
			(end -0.12065 -0.2794)
			(stroke
				(width 0.1)
				(type default)
			)
			(layer "F.Fab")
		)
		(pad "1" smd circle
			(at -0.40005 0 270)
			(size 0 0)
			(layers "F.Cu" "F.Mask" "F.Paste")
			(net "NC_PVDD11_S3_P1_IMON6")
		)
		(pad "2" smd circle
			(at 0.40005 0 270)
			(size 0 0)
			(layers "F.Cu" "F.Mask" "F.Paste")
			(net "GND")
		)
	)
)
